FILE_TYPE=LIBRARY_PARTS;
primitive 'SCONN288_ADR50017P087CC';
  pin
    'VIN_MGMT':
      PIN_NUMBER='(3,0,0)';
      PINUSE='POWER';
      NO_LOAD_CHECK='Both';
      NO_IO_CHECK='Both';
      NO_ASSERT_CHECK='TRUE';
      NO_DIR_CHECK='TRUE';
      ALLOW_CONNECT='TRUE';
    'RFU0':
      PIN_NUMBER='(2,0,0)';
      OUTPUT_TYPE='(TS,TS)';
      INPUT_LOAD='(-0.01,0.01)';
      OUTPUT_LOAD='(1.0,-1.0)';
    'RFU1':
      PIN_NUMBER='(144,0,0)';
      OUTPUT_TYPE='(TS,TS)';
      INPUT_LOAD='(-0.01,0.01)';
      OUTPUT_LOAD='(1.0,-1.0)';
    'RFU2':
      PIN_NUMBER='(149,0,0)';
      OUTPUT_TYPE='(TS,TS)';
      INPUT_LOAD='(-0.01,0.01)';
      OUTPUT_LOAD='(1.0,-1.0)';
    'RFU3':
      PIN_NUMBER='(150,0,0)';
      OUTPUT_TYPE='(TS,TS)';
      INPUT_LOAD='(-0.01,0.01)';
      OUTPUT_LOAD='(1.0,-1.0)';
    'RFU4':
      PIN_NUMBER='(220,0,0)';
      OUTPUT_TYPE='(TS,TS)';
      INPUT_LOAD='(-0.01,0.01)';
      OUTPUT_LOAD='(1.0,-1.0)';
    'RFU5':
      PIN_NUMBER='(231,0,0)';
      OUTPUT_TYPE='(TS,TS)';
      INPUT_LOAD='(-0.01,0.01)';
      OUTPUT_LOAD='(1.0,-1.0)';
    'RFU6':
      PIN_NUMBER='(232,0,0)';
      OUTPUT_TYPE='(TS,TS)';
      INPUT_LOAD='(-0.01,0.01)';
      OUTPUT_LOAD='(1.0,-1.0)';
    '-RESET':
      PIN_NUMBER='(207,0,0)';
      INPUT_LOAD='(-0.01,0.01)';
    '-PWR_GOOD||FAIL':
      PIN_NUMBER='(147,0,0)';
      BIDIRECTIONAL='TRUE';
      INPUT_LOAD='(-0.01,0.01)';
      OUTPUT_LOAD='(1.0,-1.0)';
    'PAR_B':
      PIN_NUMBER='(227,0,0)';
      INPUT_LOAD='(-0.01,0.01)';
    'PAR_A':
      PIN_NUMBER='(74,0,0)';
      INPUT_LOAD='(-0.01,0.01)';
    '-LBS||RSP_B':
      PIN_NUMBER='(87,0,0)';
      OUTPUT_LOAD='(1.0,-1.0)';
    '-LBD||RSP_A':
      PIN_NUMBER='(86,0,0)';
      OUTPUT_LOAD='(1.0,-1.0)';
    'HSDA':
      PIN_NUMBER='(5,0,0)';
      BIDIRECTIONAL='TRUE';
      INPUT_LOAD='(-0.01,0.01)';
      OUTPUT_LOAD='(1.0,-1.0)';
    'HSCL':
      PIN_NUMBER='(4,0,0)';
      INPUT_LOAD='(-0.01,0.01)';
    'HSA':
      PIN_NUMBER='(148,0,0)';
      INPUT_LOAD='(-0.01,0.01)';
    'DQ0_B':
      PIN_NUMBER='(100,0,0)';
      BIDIRECTIONAL='TRUE';
      INPUT_LOAD='(-0.01,0.01)';
      OUTPUT_LOAD='(1.0,-1.0)';
    'DQ1_B':
      PIN_NUMBER='(102,0,0)';
      BIDIRECTIONAL='TRUE';
      INPUT_LOAD='(-0.01,0.01)';
      OUTPUT_LOAD='(1.0,-1.0)';
    'DQ2_B':
      PIN_NUMBER='(245,0,0)';
      BIDIRECTIONAL='TRUE';
      INPUT_LOAD='(-0.01,0.01)';
      OUTPUT_LOAD='(1.0,-1.0)';
    'DQ3_B':
      PIN_NUMBER='(247,0,0)';
      BIDIRECTIONAL='TRUE';
      INPUT_LOAD='(-0.01,0.01)';
      OUTPUT_LOAD='(1.0,-1.0)';
    'DQ4_B':
      PIN_NUMBER='(107,0,0)';
      BIDIRECTIONAL='TRUE';
      INPUT_LOAD='(-0.01,0.01)';
      OUTPUT_LOAD='(1.0,-1.0)';
    'DQ5_B':
      PIN_NUMBER='(109,0,0)';
      BIDIRECTIONAL='TRUE';
      INPUT_LOAD='(-0.01,0.01)';
      OUTPUT_LOAD='(1.0,-1.0)';
    'DQ6_B':
      PIN_NUMBER='(252,0,0)';
      BIDIRECTIONAL='TRUE';
      INPUT_LOAD='(-0.01,0.01)';
      OUTPUT_LOAD='(1.0,-1.0)';
    'DQ7_B':
      PIN_NUMBER='(254,0,0)';
      BIDIRECTIONAL='TRUE';
      INPUT_LOAD='(-0.01,0.01)';
      OUTPUT_LOAD='(1.0,-1.0)';
    'DQ8_B':
      PIN_NUMBER='(111,0,0)';
      BIDIRECTIONAL='TRUE';
      INPUT_LOAD='(-0.01,0.01)';
      OUTPUT_LOAD='(1.0,-1.0)';
    'DQ9_B':
      PIN_NUMBER='(113,0,0)';
      BIDIRECTIONAL='TRUE';
      INPUT_LOAD='(-0.01,0.01)';
      OUTPUT_LOAD='(1.0,-1.0)';
    'DQ10_B':
      PIN_NUMBER='(256,0,0)';
      BIDIRECTIONAL='TRUE';
      INPUT_LOAD='(-0.01,0.01)';
      OUTPUT_LOAD='(1.0,-1.0)';
    'DQ11_B':
      PIN_NUMBER='(258,0,0)';
      BIDIRECTIONAL='TRUE';
      INPUT_LOAD='(-0.01,0.01)';
      OUTPUT_LOAD='(1.0,-1.0)';
    'DQ12_B':
      PIN_NUMBER='(118,0,0)';
      BIDIRECTIONAL='TRUE';
      INPUT_LOAD='(-0.01,0.01)';
      OUTPUT_LOAD='(1.0,-1.0)';
    'DQ13_B':
      PIN_NUMBER='(120,0,0)';
      BIDIRECTIONAL='TRUE';
      INPUT_LOAD='(-0.01,0.01)';
      OUTPUT_LOAD='(1.0,-1.0)';
    'DQ14_B':
      PIN_NUMBER='(263,0,0)';
      BIDIRECTIONAL='TRUE';
      INPUT_LOAD='(-0.01,0.01)';
      OUTPUT_LOAD='(1.0,-1.0)';
    'DQ15_B':
      PIN_NUMBER='(265,0,0)';
      BIDIRECTIONAL='TRUE';
      INPUT_LOAD='(-0.01,0.01)';
      OUTPUT_LOAD='(1.0,-1.0)';
    'DQ16_B':
      PIN_NUMBER='(122,0,0)';
      BIDIRECTIONAL='TRUE';
      INPUT_LOAD='(-0.01,0.01)';
      OUTPUT_LOAD='(1.0,-1.0)';
    'DQ17_B':
      PIN_NUMBER='(124,0,0)';
      BIDIRECTIONAL='TRUE';
      INPUT_LOAD='(-0.01,0.01)';
      OUTPUT_LOAD='(1.0,-1.0)';
    'DQ18_B':
      PIN_NUMBER='(267,0,0)';
      BIDIRECTIONAL='TRUE';
      INPUT_LOAD='(-0.01,0.01)';
      OUTPUT_LOAD='(1.0,-1.0)';
    'DQ19_B':
      PIN_NUMBER='(269,0,0)';
      BIDIRECTIONAL='TRUE';
      INPUT_LOAD='(-0.01,0.01)';
      OUTPUT_LOAD='(1.0,-1.0)';
    'DQ20_B':
      PIN_NUMBER='(129,0,0)';
      BIDIRECTIONAL='TRUE';
      INPUT_LOAD='(-0.01,0.01)';
      OUTPUT_LOAD='(1.0,-1.0)';
    'DQ21_B':
      PIN_NUMBER='(131,0,0)';
      BIDIRECTIONAL='TRUE';
      INPUT_LOAD='(-0.01,0.01)';
      OUTPUT_LOAD='(1.0,-1.0)';
    'DQ22_B':
      PIN_NUMBER='(274,0,0)';
      BIDIRECTIONAL='TRUE';
      INPUT_LOAD='(-0.01,0.01)';
      OUTPUT_LOAD='(1.0,-1.0)';
    'DQ23_B':
      PIN_NUMBER='(276,0,0)';
      BIDIRECTIONAL='TRUE';
      INPUT_LOAD='(-0.01,0.01)';
      OUTPUT_LOAD='(1.0,-1.0)';
    'DQ24_B':
      PIN_NUMBER='(133,0,0)';
      BIDIRECTIONAL='TRUE';
      INPUT_LOAD='(-0.01,0.01)';
      OUTPUT_LOAD='(1.0,-1.0)';
    'DQ25_B':
      PIN_NUMBER='(135,0,0)';
      BIDIRECTIONAL='TRUE';
      INPUT_LOAD='(-0.01,0.01)';
      OUTPUT_LOAD='(1.0,-1.0)';
    'DQ26_B':
      PIN_NUMBER='(278,0,0)';
      BIDIRECTIONAL='TRUE';
      INPUT_LOAD='(-0.01,0.01)';
      OUTPUT_LOAD='(1.0,-1.0)';
    'DQ27_B':
      PIN_NUMBER='(280,0,0)';
      BIDIRECTIONAL='TRUE';
      INPUT_LOAD='(-0.01,0.01)';
      OUTPUT_LOAD='(1.0,-1.0)';
    'DQ28_B':
      PIN_NUMBER='(140,0,0)';
      BIDIRECTIONAL='TRUE';
      INPUT_LOAD='(-0.01,0.01)';
      OUTPUT_LOAD='(1.0,-1.0)';
    'DQ29_B':
      PIN_NUMBER='(142,0,0)';
      BIDIRECTIONAL='TRUE';
      INPUT_LOAD='(-0.01,0.01)';
      OUTPUT_LOAD='(1.0,-1.0)';
    'DQ30_B':
      PIN_NUMBER='(285,0,0)';
      BIDIRECTIONAL='TRUE';
      INPUT_LOAD='(-0.01,0.01)';
      OUTPUT_LOAD='(1.0,-1.0)';
    'DQ31_B':
      PIN_NUMBER='(287,0,0)';
      BIDIRECTIONAL='TRUE';
      INPUT_LOAD='(-0.01,0.01)';
      OUTPUT_LOAD='(1.0,-1.0)';
    'DQ0_A':
      PIN_NUMBER='(7,0,0)';
      BIDIRECTIONAL='TRUE';
      INPUT_LOAD='(-0.01,0.01)';
      OUTPUT_LOAD='(1.0,-1.0)';
    'DQ1_A':
      PIN_NUMBER='(9,0,0)';
      BIDIRECTIONAL='TRUE';
      INPUT_LOAD='(-0.01,0.01)';
      OUTPUT_LOAD='(1.0,-1.0)';
    'DQ2_A':
      PIN_NUMBER='(152,0,0)';
      BIDIRECTIONAL='TRUE';
      INPUT_LOAD='(-0.01,0.01)';
      OUTPUT_LOAD='(1.0,-1.0)';
    'DQ3_A':
      PIN_NUMBER='(154,0,0)';
      BIDIRECTIONAL='TRUE';
      INPUT_LOAD='(-0.01,0.01)';
      OUTPUT_LOAD='(1.0,-1.0)';
    'DQ4_A':
      PIN_NUMBER='(14,0,0)';
      BIDIRECTIONAL='TRUE';
      INPUT_LOAD='(-0.01,0.01)';
      OUTPUT_LOAD='(1.0,-1.0)';
    'DQ5_A':
      PIN_NUMBER='(16,0,0)';
      BIDIRECTIONAL='TRUE';
      INPUT_LOAD='(-0.01,0.01)';
      OUTPUT_LOAD='(1.0,-1.0)';
    'DQ6_A':
      PIN_NUMBER='(159,0,0)';
      BIDIRECTIONAL='TRUE';
      INPUT_LOAD='(-0.01,0.01)';
      OUTPUT_LOAD='(1.0,-1.0)';
    'DQ7_A':
      PIN_NUMBER='(161,0,0)';
      BIDIRECTIONAL='TRUE';
      INPUT_LOAD='(-0.01,0.01)';
      OUTPUT_LOAD='(1.0,-1.0)';
    'DQ8_A':
      PIN_NUMBER='(18,0,0)';
      BIDIRECTIONAL='TRUE';
      INPUT_LOAD='(-0.01,0.01)';
      OUTPUT_LOAD='(1.0,-1.0)';
    'DQ9_A':
      PIN_NUMBER='(20,0,0)';
      BIDIRECTIONAL='TRUE';
      INPUT_LOAD='(-0.01,0.01)';
      OUTPUT_LOAD='(1.0,-1.0)';
    'DQ10_A':
      PIN_NUMBER='(163,0,0)';
      BIDIRECTIONAL='TRUE';
      INPUT_LOAD='(-0.01,0.01)';
      OUTPUT_LOAD='(1.0,-1.0)';
    'DQ11_A':
      PIN_NUMBER='(165,0,0)';
      BIDIRECTIONAL='TRUE';
      INPUT_LOAD='(-0.01,0.01)';
      OUTPUT_LOAD='(1.0,-1.0)';
    'DQ12_A':
      PIN_NUMBER='(25,0,0)';
      BIDIRECTIONAL='TRUE';
      INPUT_LOAD='(-0.01,0.01)';
      OUTPUT_LOAD='(1.0,-1.0)';
    'DQ13_A':
      PIN_NUMBER='(27,0,0)';
      BIDIRECTIONAL='TRUE';
      INPUT_LOAD='(-0.01,0.01)';
      OUTPUT_LOAD='(1.0,-1.0)';
    'DQ14_A':
      PIN_NUMBER='(170,0,0)';
      BIDIRECTIONAL='TRUE';
      INPUT_LOAD='(-0.01,0.01)';
      OUTPUT_LOAD='(1.0,-1.0)';
    'DQ15_A':
      PIN_NUMBER='(172,0,0)';
      BIDIRECTIONAL='TRUE';
      INPUT_LOAD='(-0.01,0.01)';
      OUTPUT_LOAD='(1.0,-1.0)';
    'DQ16_A':
      PIN_NUMBER='(29,0,0)';
      BIDIRECTIONAL='TRUE';
      INPUT_LOAD='(-0.01,0.01)';
      OUTPUT_LOAD='(1.0,-1.0)';
    'DQ17_A':
      PIN_NUMBER='(31,0,0)';
      BIDIRECTIONAL='TRUE';
      INPUT_LOAD='(-0.01,0.01)';
      OUTPUT_LOAD='(1.0,-1.0)';
    'DQ18_A':
      PIN_NUMBER='(174,0,0)';
      BIDIRECTIONAL='TRUE';
      INPUT_LOAD='(-0.01,0.01)';
      OUTPUT_LOAD='(1.0,-1.0)';
    'DQ19_A':
      PIN_NUMBER='(176,0,0)';
      BIDIRECTIONAL='TRUE';
      INPUT_LOAD='(-0.01,0.01)';
      OUTPUT_LOAD='(1.0,-1.0)';
    'DQ20_A':
      PIN_NUMBER='(36,0,0)';
      BIDIRECTIONAL='TRUE';
      INPUT_LOAD='(-0.01,0.01)';
      OUTPUT_LOAD='(1.0,-1.0)';
    'DQ21_A':
      PIN_NUMBER='(38,0,0)';
      BIDIRECTIONAL='TRUE';
      INPUT_LOAD='(-0.01,0.01)';
      OUTPUT_LOAD='(1.0,-1.0)';
    'DQ22_A':
      PIN_NUMBER='(181,0,0)';
      BIDIRECTIONAL='TRUE';
      INPUT_LOAD='(-0.01,0.01)';
      OUTPUT_LOAD='(1.0,-1.0)';
    'DQ23_A':
      PIN_NUMBER='(183,0,0)';
      BIDIRECTIONAL='TRUE';
      INPUT_LOAD='(-0.01,0.01)';
      OUTPUT_LOAD='(1.0,-1.0)';
    'DQ24_A':
      PIN_NUMBER='(40,0,0)';
      BIDIRECTIONAL='TRUE';
      INPUT_LOAD='(-0.01,0.01)';
      OUTPUT_LOAD='(1.0,-1.0)';
    'DQ25_A':
      PIN_NUMBER='(42,0,0)';
      BIDIRECTIONAL='TRUE';
      INPUT_LOAD='(-0.01,0.01)';
      OUTPUT_LOAD='(1.0,-1.0)';
    'DQ26_A':
      PIN_NUMBER='(185,0,0)';
      BIDIRECTIONAL='TRUE';
      INPUT_LOAD='(-0.01,0.01)';
      OUTPUT_LOAD='(1.0,-1.0)';
    'DQ27_A':
      PIN_NUMBER='(187,0,0)';
      BIDIRECTIONAL='TRUE';
      INPUT_LOAD='(-0.01,0.01)';
      OUTPUT_LOAD='(1.0,-1.0)';
    'DQ28_A':
      PIN_NUMBER='(47,0,0)';
      BIDIRECTIONAL='TRUE';
      INPUT_LOAD='(-0.01,0.01)';
      OUTPUT_LOAD='(1.0,-1.0)';
    'DQ29_A':
      PIN_NUMBER='(49,0,0)';
      BIDIRECTIONAL='TRUE';
      INPUT_LOAD='(-0.01,0.01)';
      OUTPUT_LOAD='(1.0,-1.0)';
    'DQ30_A':
      PIN_NUMBER='(192,0,0)';
      BIDIRECTIONAL='TRUE';
      INPUT_LOAD='(-0.01,0.01)';
      OUTPUT_LOAD='(1.0,-1.0)';
    '-CS1_B':
      PIN_NUMBER='(229,0,0)';
      INPUT_LOAD='(-0.01,0.01)';
    '-CS1_A':
      PIN_NUMBER='(209,0,0)';
      INPUT_LOAD='(-0.01,0.01)';
    '-CS0_B':
      PIN_NUMBER='(84,0,0)';
      INPUT_LOAD='(-0.01,0.01)';
    '-CS0_A':
      PIN_NUMBER='(64,0,0)';
      INPUT_LOAD='(-0.01,0.01)';
    'CK_T':
      PIN_NUMBER='(217,0,0)';
      INPUT_LOAD='(-0.01,0.01)';
    'CK_C':
      PIN_NUMBER='(218,0,0)';
      INPUT_LOAD='(-0.01,0.01)';
    'CB0_B':
      PIN_NUMBER='(96,0,0)';
      BIDIRECTIONAL='TRUE';
      INPUT_LOAD='(-0.01,0.01)';
      OUTPUT_LOAD='(1.0,-1.0)';
    'CB1_B':
      PIN_NUMBER='(98,0,0)';
      BIDIRECTIONAL='TRUE';
      INPUT_LOAD='(-0.01,0.01)';
      OUTPUT_LOAD='(1.0,-1.0)';
    'CB2_B':
      PIN_NUMBER='(241,0,0)';
      BIDIRECTIONAL='TRUE';
      INPUT_LOAD='(-0.01,0.01)';
      OUTPUT_LOAD='(1.0,-1.0)';
    'CB3_B':
      PIN_NUMBER='(243,0,0)';
      BIDIRECTIONAL='TRUE';
      INPUT_LOAD='(-0.01,0.01)';
      OUTPUT_LOAD='(1.0,-1.0)';
    'CB4_B':
      PIN_NUMBER='(89,0,0)';
      BIDIRECTIONAL='TRUE';
      INPUT_LOAD='(-0.01,0.01)';
      OUTPUT_LOAD='(1.0,-1.0)';
    'CB5_B':
      PIN_NUMBER='(91,0,0)';
      BIDIRECTIONAL='TRUE';
      INPUT_LOAD='(-0.01,0.01)';
      OUTPUT_LOAD='(1.0,-1.0)';
    'CB6_B':
      PIN_NUMBER='(234,0,0)';
      BIDIRECTIONAL='TRUE';
      INPUT_LOAD='(-0.01,0.01)';
      OUTPUT_LOAD='(1.0,-1.0)';
    'CB0_A':
      PIN_NUMBER='(51,0,0)';
      BIDIRECTIONAL='TRUE';
      INPUT_LOAD='(-0.01,0.01)';
      OUTPUT_LOAD='(1.0,-1.0)';
    'CB2_A':
      PIN_NUMBER='(196,0,0)';
      BIDIRECTIONAL='TRUE';
      INPUT_LOAD='(-0.01,0.01)';
      OUTPUT_LOAD='(1.0,-1.0)';
    'CB3_A':
      PIN_NUMBER='(198,0,0)';
      BIDIRECTIONAL='TRUE';
      INPUT_LOAD='(-0.01,0.01)';
      OUTPUT_LOAD='(1.0,-1.0)';
    'CB5_A':
      PIN_NUMBER='(60,0,0)';
      BIDIRECTIONAL='TRUE';
      INPUT_LOAD='(-0.01,0.01)';
      OUTPUT_LOAD='(1.0,-1.0)';
    'CB6_A':
      PIN_NUMBER='(203,0,0)';
      BIDIRECTIONAL='TRUE';
      INPUT_LOAD='(-0.01,0.01)';
      OUTPUT_LOAD='(1.0,-1.0)';
    'CA6_B':
      PIN_NUMBER='(82,0,0)';
      INPUT_LOAD='(-0.01,0.01)';
    'CA6_A':
      PIN_NUMBER='(72,0,0)';
      INPUT_LOAD='(-0.01,0.01)';
    'CA5_B':
      PIN_NUMBER='(225,0,0)';
      INPUT_LOAD='(-0.01,0.01)';
    'CA5_A':
      PIN_NUMBER='(215,0,0)';
      INPUT_LOAD='(-0.01,0.01)';
    'CA4_B':
      PIN_NUMBER='(80,0,0)';
      INPUT_LOAD='(-0.01,0.01)';
    'CA4_A':
      PIN_NUMBER='(70,0,0)';
      INPUT_LOAD='(-0.01,0.01)';
    'CA3_B':
      PIN_NUMBER='(223,0,0)';
      INPUT_LOAD='(-0.01,0.01)';
    'CA3_A':
      PIN_NUMBER='(213,0,0)';
      INPUT_LOAD='(-0.01,0.01)';
    'CA2_B':
      PIN_NUMBER='(78,0,0)';
      INPUT_LOAD='(-0.01,0.01)';
    'CA2_A':
      PIN_NUMBER='(68,0,0)';
      INPUT_LOAD='(-0.01,0.01)';
    'CA1_B':
      PIN_NUMBER='(221,0,0)';
      INPUT_LOAD='(-0.01,0.01)';
    'CA1_A':
      PIN_NUMBER='(211,0,0)';
      INPUT_LOAD='(-0.01,0.01)';
    'CA0_B':
      PIN_NUMBER='(76,0,0)';
      INPUT_LOAD='(-0.01,0.01)';
    'CA0_A':
      PIN_NUMBER='(66,0,0)';
      INPUT_LOAD='(-0.01,0.01)';
    '-ALERT':
      PIN_NUMBER='(62,0,0)';
      OUTPUT_LOAD='(1.0,-1.0)';
    'CB7_B':
      PIN_NUMBER='(236,0,0)';
      BIDIRECTIONAL='TRUE';
      INPUT_LOAD='(-0.01,0.01)';
      OUTPUT_LOAD='(1.0,-1.0)';
    'CB1_A':
      PIN_NUMBER='(53,0,0)';
      BIDIRECTIONAL='TRUE';
      INPUT_LOAD='(-0.01,0.01)';
      OUTPUT_LOAD='(1.0,-1.0)';
    'CB4_A':
      PIN_NUMBER='(58,0,0)';
      BIDIRECTIONAL='TRUE';
      INPUT_LOAD='(-0.01,0.01)';
      OUTPUT_LOAD='(1.0,-1.0)';
    'CB7_A':
      PIN_NUMBER='(205,0,0)';
      BIDIRECTIONAL='TRUE';
      INPUT_LOAD='(-0.01,0.01)';
      OUTPUT_LOAD='(1.0,-1.0)';
    'DQ31_A':
      PIN_NUMBER='(194,0,0)';
      BIDIRECTIONAL='TRUE';
      INPUT_LOAD='(-0.01,0.01)';
      OUTPUT_LOAD='(1.0,-1.0)';
    '-DQS9_B_T||TDQS9_B_T||DBI4_B':
      PIN_NUMBER='(0,93,0)';
      BIDIRECTIONAL='TRUE';
      INPUT_LOAD='(-0.01,0.01)';
      OUTPUT_LOAD='(1.0,-1.0)';
    'DQS9_B_C||TDQS9_B_C':
      PIN_NUMBER='(0,94,0)';
      BIDIRECTIONAL='TRUE';
      INPUT_LOAD='(-0.01,0.01)';
      OUTPUT_LOAD='(1.0,-1.0)';
    'DQS9_A_T||TDQS9_A_T':
      PIN_NUMBER='(0,201,0)';
      BIDIRECTIONAL='TRUE';
      INPUT_LOAD='(-0.01,0.01)';
      OUTPUT_LOAD='(1.0,-1.0)';
    'DQS9_A_C||TDQS9_A_C':
      PIN_NUMBER='(0,200,0)';
      BIDIRECTIONAL='TRUE';
      INPUT_LOAD='(-0.01,0.01)';
      OUTPUT_LOAD='(1.0,-1.0)';
    'DQS8_A_T||TDQS8_A_T':
      PIN_NUMBER='(0,190,0)';
      BIDIRECTIONAL='TRUE';
      INPUT_LOAD='(-0.01,0.01)';
      OUTPUT_LOAD='(1.0,-1.0)';
    'DQS8_A_C||TDQS8_A_C':
      PIN_NUMBER='(0,189,0)';
      BIDIRECTIONAL='TRUE';
      INPUT_LOAD='(-0.01,0.01)';
      OUTPUT_LOAD='(1.0,-1.0)';
    'DQS7_B_C||TDQS7_B_C':
      PIN_NUMBER='(0,271,0)';
      BIDIRECTIONAL='TRUE';
      INPUT_LOAD='(-0.01,0.01)';
      OUTPUT_LOAD='(1.0,-1.0)';
    'DQS7_A_T||TDQS7_A_T':
      PIN_NUMBER='(0,179,0)';
      BIDIRECTIONAL='TRUE';
      INPUT_LOAD='(-0.01,0.01)';
      OUTPUT_LOAD='(1.0,-1.0)';
    'DQS6_B_T||TDQS6_B_T':
      PIN_NUMBER='(0,261,0)';
      BIDIRECTIONAL='TRUE';
      INPUT_LOAD='(-0.01,0.01)';
      OUTPUT_LOAD='(1.0,-1.0)';
    'DQS6_B_C||TDQS6_B_C':
      PIN_NUMBER='(0,260,0)';
      BIDIRECTIONAL='TRUE';
      INPUT_LOAD='(-0.01,0.01)';
      OUTPUT_LOAD='(1.0,-1.0)';
    'DQS6_A_C||TDQS6_A_C||DQS6_A_T||TDQS6_A_T':
      PIN_NUMBER='(0,167,0)';
      BIDIRECTIONAL='TRUE';
      INPUT_LOAD='(-0.01,0.01)';
      OUTPUT_LOAD='(1.0,-1.0)';
    'DQS5_B_T||TDQS5_B_T':
      PIN_NUMBER='(0,250,0)';
      BIDIRECTIONAL='TRUE';
      INPUT_LOAD='(-0.01,0.01)';
      OUTPUT_LOAD='(1.0,-1.0)';
    'DQS5_B_C||TDQS5_B_C':
      PIN_NUMBER='(0,249,0)';
      BIDIRECTIONAL='TRUE';
      INPUT_LOAD='(-0.01,0.01)';
      OUTPUT_LOAD='(1.0,-1.0)';
    'DQS5_A_T||TDQS5_A_T':
      PIN_NUMBER='(0,157,0)';
      BIDIRECTIONAL='TRUE';
      INPUT_LOAD='(-0.01,0.01)';
      OUTPUT_LOAD='(1.0,-1.0)';
    'DQS5_A_C||TDQS5_A_C||DQS5_A_T||TDQS5_A_T':
      PIN_NUMBER='(0,156,0)';
      BIDIRECTIONAL='TRUE';
      INPUT_LOAD='(-0.01,0.01)';
      OUTPUT_LOAD='(1.0,-1.0)';
    'DQS4_B_T':
      PIN_NUMBER='(0,239,0)';
      BIDIRECTIONAL='TRUE';
      INPUT_LOAD='(-0.01,0.01)';
      OUTPUT_LOAD='(1.0,-1.0)';
    'DQS4_B_C':
      PIN_NUMBER='(0,238,0)';
      BIDIRECTIONAL='TRUE';
      INPUT_LOAD='(-0.01,0.01)';
      OUTPUT_LOAD='(1.0,-1.0)';
    'DQS4_A_T':
      PIN_NUMBER='(0,55,0)';
      BIDIRECTIONAL='TRUE';
      INPUT_LOAD='(-0.01,0.01)';
      OUTPUT_LOAD='(1.0,-1.0)';
    'DQS4_A_C':
      PIN_NUMBER='(0,56,0)';
      BIDIRECTIONAL='TRUE';
      INPUT_LOAD='(-0.01,0.01)';
      OUTPUT_LOAD='(1.0,-1.0)';
    'DQS3_B_T':
      PIN_NUMBER='(0,137,0)';
      BIDIRECTIONAL='TRUE';
      INPUT_LOAD='(-0.01,0.01)';
      OUTPUT_LOAD='(1.0,-1.0)';
    'DQS3_B_C':
      PIN_NUMBER='(0,138,0)';
      BIDIRECTIONAL='TRUE';
      INPUT_LOAD='(-0.01,0.01)';
      OUTPUT_LOAD='(1.0,-1.0)';
    'DQS3_A_T':
      PIN_NUMBER='(0,44,0)';
      BIDIRECTIONAL='TRUE';
      INPUT_LOAD='(-0.01,0.01)';
      OUTPUT_LOAD='(1.0,-1.0)';
    'DQS3_A_C':
      PIN_NUMBER='(0,45,0)';
      BIDIRECTIONAL='TRUE';
      INPUT_LOAD='(-0.01,0.01)';
      OUTPUT_LOAD='(1.0,-1.0)';
    'DQS2_B_T':
      PIN_NUMBER='(0,126,0)';
      BIDIRECTIONAL='TRUE';
      INPUT_LOAD='(-0.01,0.01)';
      OUTPUT_LOAD='(1.0,-1.0)';
    'DQS2_B_C':
      PIN_NUMBER='(0,127,0)';
      BIDIRECTIONAL='TRUE';
      INPUT_LOAD='(-0.01,0.01)';
      OUTPUT_LOAD='(1.0,-1.0)';
    'DQS2_A_T':
      PIN_NUMBER='(0,33,0)';
      BIDIRECTIONAL='TRUE';
      INPUT_LOAD='(-0.01,0.01)';
      OUTPUT_LOAD='(1.0,-1.0)';
    'DQS2_A_C':
      PIN_NUMBER='(0,34,0)';
      BIDIRECTIONAL='TRUE';
      INPUT_LOAD='(-0.01,0.01)';
      OUTPUT_LOAD='(1.0,-1.0)';
    'DQS1_B_T':
      PIN_NUMBER='(0,115,0)';
      BIDIRECTIONAL='TRUE';
      INPUT_LOAD='(-0.01,0.01)';
      OUTPUT_LOAD='(1.0,-1.0)';
    'DQS1_B_C':
      PIN_NUMBER='(0,116,0)';
      BIDIRECTIONAL='TRUE';
      INPUT_LOAD='(-0.01,0.01)';
      OUTPUT_LOAD='(1.0,-1.0)';
    'DQS1_A_T':
      PIN_NUMBER='(0,22,0)';
      BIDIRECTIONAL='TRUE';
      INPUT_LOAD='(-0.01,0.01)';
      OUTPUT_LOAD='(1.0,-1.0)';
    'DQS1_A_C':
      PIN_NUMBER='(0,23,0)';
      BIDIRECTIONAL='TRUE';
      INPUT_LOAD='(-0.01,0.01)';
      OUTPUT_LOAD='(1.0,-1.0)';
    'DQS0_B_T':
      PIN_NUMBER='(0,104,0)';
      BIDIRECTIONAL='TRUE';
      INPUT_LOAD='(-0.01,0.01)';
      OUTPUT_LOAD='(1.0,-1.0)';
    'DQS0_B_C':
      PIN_NUMBER='(0,105,0)';
      BIDIRECTIONAL='TRUE';
      INPUT_LOAD='(-0.01,0.01)';
      OUTPUT_LOAD='(1.0,-1.0)';
    'DQS0_A_T':
      PIN_NUMBER='(0,11,0)';
      BIDIRECTIONAL='TRUE';
      INPUT_LOAD='(-0.01,0.01)';
      OUTPUT_LOAD='(1.0,-1.0)';
    'DQS0_A_C':
      PIN_NUMBER='(0,12,0)';
      BIDIRECTIONAL='TRUE';
      INPUT_LOAD='(-0.01,0.01)';
      OUTPUT_LOAD='(1.0,-1.0)';
    'DQS7_B_T||TDQS7_B_T':
      PIN_NUMBER='(0,272,0)';
      BIDIRECTIONAL='TRUE';
      INPUT_LOAD='(-0.01,0.01)';
      OUTPUT_LOAD='(1.0,-1.0)';
    'DQS8_B_C||TDQS8_B_C':
      PIN_NUMBER='(0,282,0)';
      BIDIRECTIONAL='TRUE';
      INPUT_LOAD='(-0.01,0.01)';
      OUTPUT_LOAD='(1.0,-1.0)';
    'DQS8_B_T||TDQS8_B_T':
      PIN_NUMBER='(0,283,0)';
      BIDIRECTIONAL='TRUE';
      INPUT_LOAD='(-0.01,0.01)';
      OUTPUT_LOAD='(1.0,-1.0)';
    'DQS6_A_T||TDQS6_A_T':
      PIN_NUMBER='(0,168,0)';
      BIDIRECTIONAL='TRUE';
      INPUT_LOAD='(-0.01,0.01)';
      OUTPUT_LOAD='(1.0,-1.0)';
    'DQS7_A_C||TDQS7_A_C':
      PIN_NUMBER='(0,178,0)';
      BIDIRECTIONAL='TRUE';
      INPUT_LOAD='(-0.01,0.01)';
      OUTPUT_LOAD='(1.0,-1.0)';
    'VSS0':
      PIN_NUMBER='(0,0,6)';
      PINUSE='POWER';
      NO_LOAD_CHECK='Both';
      NO_IO_CHECK='Both';
      NO_ASSERT_CHECK='TRUE';
      NO_DIR_CHECK='TRUE';
      ALLOW_CONNECT='TRUE';
    'VSS1':
      PIN_NUMBER='(0,0,8)';
      PINUSE='POWER';
      NO_LOAD_CHECK='Both';
      NO_IO_CHECK='Both';
      NO_ASSERT_CHECK='TRUE';
      NO_DIR_CHECK='TRUE';
      ALLOW_CONNECT='TRUE';
    'VSS2':
      PIN_NUMBER='(0,0,10)';
      PINUSE='POWER';
      NO_LOAD_CHECK='Both';
      NO_IO_CHECK='Both';
      NO_ASSERT_CHECK='TRUE';
      NO_DIR_CHECK='TRUE';
      ALLOW_CONNECT='TRUE';
    'VSS3':
      PIN_NUMBER='(0,0,13)';
      PINUSE='POWER';
      NO_LOAD_CHECK='Both';
      NO_IO_CHECK='Both';
      NO_ASSERT_CHECK='TRUE';
      NO_DIR_CHECK='TRUE';
      ALLOW_CONNECT='TRUE';
    'VSS4':
      PIN_NUMBER='(0,0,15)';
      PINUSE='POWER';
      NO_LOAD_CHECK='Both';
      NO_IO_CHECK='Both';
      NO_ASSERT_CHECK='TRUE';
      NO_DIR_CHECK='TRUE';
      ALLOW_CONNECT='TRUE';
    'VSS5':
      PIN_NUMBER='(0,0,17)';
      PINUSE='POWER';
      NO_LOAD_CHECK='Both';
      NO_IO_CHECK='Both';
      NO_ASSERT_CHECK='TRUE';
      NO_DIR_CHECK='TRUE';
      ALLOW_CONNECT='TRUE';
    'VSS6':
      PIN_NUMBER='(0,0,19)';
      PINUSE='POWER';
      NO_LOAD_CHECK='Both';
      NO_IO_CHECK='Both';
      NO_ASSERT_CHECK='TRUE';
      NO_DIR_CHECK='TRUE';
      ALLOW_CONNECT='TRUE';
    'VSS7':
      PIN_NUMBER='(0,0,21)';
      PINUSE='POWER';
      NO_LOAD_CHECK='Both';
      NO_IO_CHECK='Both';
      NO_ASSERT_CHECK='TRUE';
      NO_DIR_CHECK='TRUE';
      ALLOW_CONNECT='TRUE';
    'VSS8':
      PIN_NUMBER='(0,0,24)';
      PINUSE='POWER';
      NO_LOAD_CHECK='Both';
      NO_IO_CHECK='Both';
      NO_ASSERT_CHECK='TRUE';
      NO_DIR_CHECK='TRUE';
      ALLOW_CONNECT='TRUE';
    'VSS9':
      PIN_NUMBER='(0,0,26)';
      PINUSE='POWER';
      NO_LOAD_CHECK='Both';
      NO_IO_CHECK='Both';
      NO_ASSERT_CHECK='TRUE';
      NO_DIR_CHECK='TRUE';
      ALLOW_CONNECT='TRUE';
    'VSS10':
      PIN_NUMBER='(0,0,28)';
      PINUSE='POWER';
      NO_LOAD_CHECK='Both';
      NO_IO_CHECK='Both';
      NO_ASSERT_CHECK='TRUE';
      NO_DIR_CHECK='TRUE';
      ALLOW_CONNECT='TRUE';
    'VSS11':
      PIN_NUMBER='(0,0,30)';
      PINUSE='POWER';
      NO_LOAD_CHECK='Both';
      NO_IO_CHECK='Both';
      NO_ASSERT_CHECK='TRUE';
      NO_DIR_CHECK='TRUE';
      ALLOW_CONNECT='TRUE';
    'VSS12':
      PIN_NUMBER='(0,0,32)';
      PINUSE='POWER';
      NO_LOAD_CHECK='Both';
      NO_IO_CHECK='Both';
      NO_ASSERT_CHECK='TRUE';
      NO_DIR_CHECK='TRUE';
      ALLOW_CONNECT='TRUE';
    'VSS13':
      PIN_NUMBER='(0,0,35)';
      PINUSE='POWER';
      NO_LOAD_CHECK='Both';
      NO_IO_CHECK='Both';
      NO_ASSERT_CHECK='TRUE';
      NO_DIR_CHECK='TRUE';
      ALLOW_CONNECT='TRUE';
    'VSS14':
      PIN_NUMBER='(0,0,37)';
      PINUSE='POWER';
      NO_LOAD_CHECK='Both';
      NO_IO_CHECK='Both';
      NO_ASSERT_CHECK='TRUE';
      NO_DIR_CHECK='TRUE';
      ALLOW_CONNECT='TRUE';
    'VSS15':
      PIN_NUMBER='(0,0,39)';
      PINUSE='POWER';
      NO_LOAD_CHECK='Both';
      NO_IO_CHECK='Both';
      NO_ASSERT_CHECK='TRUE';
      NO_DIR_CHECK='TRUE';
      ALLOW_CONNECT='TRUE';
    'VSS16':
      PIN_NUMBER='(0,0,41)';
      PINUSE='POWER';
      NO_LOAD_CHECK='Both';
      NO_IO_CHECK='Both';
      NO_ASSERT_CHECK='TRUE';
      NO_DIR_CHECK='TRUE';
      ALLOW_CONNECT='TRUE';
    'VSS17':
      PIN_NUMBER='(0,0,43)';
      PINUSE='POWER';
      NO_LOAD_CHECK='Both';
      NO_IO_CHECK='Both';
      NO_ASSERT_CHECK='TRUE';
      NO_DIR_CHECK='TRUE';
      ALLOW_CONNECT='TRUE';
    'VSS18':
      PIN_NUMBER='(0,0,46)';
      PINUSE='POWER';
      NO_LOAD_CHECK='Both';
      NO_IO_CHECK='Both';
      NO_ASSERT_CHECK='TRUE';
      NO_DIR_CHECK='TRUE';
      ALLOW_CONNECT='TRUE';
    'VSS19':
      PIN_NUMBER='(0,0,48)';
      PINUSE='POWER';
      NO_LOAD_CHECK='Both';
      NO_IO_CHECK='Both';
      NO_ASSERT_CHECK='TRUE';
      NO_DIR_CHECK='TRUE';
      ALLOW_CONNECT='TRUE';
    'VSS20':
      PIN_NUMBER='(0,0,50)';
      PINUSE='POWER';
      NO_LOAD_CHECK='Both';
      NO_IO_CHECK='Both';
      NO_ASSERT_CHECK='TRUE';
      NO_DIR_CHECK='TRUE';
      ALLOW_CONNECT='TRUE';
    'VSS21':
      PIN_NUMBER='(0,0,52)';
      PINUSE='POWER';
      NO_LOAD_CHECK='Both';
      NO_IO_CHECK='Both';
      NO_ASSERT_CHECK='TRUE';
      NO_DIR_CHECK='TRUE';
      ALLOW_CONNECT='TRUE';
    'VSS22':
      PIN_NUMBER='(0,0,54)';
      PINUSE='POWER';
      NO_LOAD_CHECK='Both';
      NO_IO_CHECK='Both';
      NO_ASSERT_CHECK='TRUE';
      NO_DIR_CHECK='TRUE';
      ALLOW_CONNECT='TRUE';
    'VSS23':
      PIN_NUMBER='(0,0,57)';
      PINUSE='POWER';
      NO_LOAD_CHECK='Both';
      NO_IO_CHECK='Both';
      NO_ASSERT_CHECK='TRUE';
      NO_DIR_CHECK='TRUE';
      ALLOW_CONNECT='TRUE';
    'VSS24':
      PIN_NUMBER='(0,0,59)';
      PINUSE='POWER';
      NO_LOAD_CHECK='Both';
      NO_IO_CHECK='Both';
      NO_ASSERT_CHECK='TRUE';
      NO_DIR_CHECK='TRUE';
      ALLOW_CONNECT='TRUE';
    'VSS25':
      PIN_NUMBER='(0,0,61)';
      PINUSE='POWER';
      NO_LOAD_CHECK='Both';
      NO_IO_CHECK='Both';
      NO_ASSERT_CHECK='TRUE';
      NO_DIR_CHECK='TRUE';
      ALLOW_CONNECT='TRUE';
    'VSS26':
      PIN_NUMBER='(0,0,63)';
      PINUSE='POWER';
      NO_LOAD_CHECK='Both';
      NO_IO_CHECK='Both';
      NO_ASSERT_CHECK='TRUE';
      NO_DIR_CHECK='TRUE';
      ALLOW_CONNECT='TRUE';
    'VSS27':
      PIN_NUMBER='(0,0,65)';
      PINUSE='POWER';
      NO_LOAD_CHECK='Both';
      NO_IO_CHECK='Both';
      NO_ASSERT_CHECK='TRUE';
      NO_DIR_CHECK='TRUE';
      ALLOW_CONNECT='TRUE';
    'VSS28':
      PIN_NUMBER='(0,0,67)';
      PINUSE='POWER';
      NO_LOAD_CHECK='Both';
      NO_IO_CHECK='Both';
      NO_ASSERT_CHECK='TRUE';
      NO_DIR_CHECK='TRUE';
      ALLOW_CONNECT='TRUE';
    'VSS29':
      PIN_NUMBER='(0,0,69)';
      PINUSE='POWER';
      NO_LOAD_CHECK='Both';
      NO_IO_CHECK='Both';
      NO_ASSERT_CHECK='TRUE';
      NO_DIR_CHECK='TRUE';
      ALLOW_CONNECT='TRUE';
    'VSS30':
      PIN_NUMBER='(0,0,71)';
      PINUSE='POWER';
      NO_LOAD_CHECK='Both';
      NO_IO_CHECK='Both';
      NO_ASSERT_CHECK='TRUE';
      NO_DIR_CHECK='TRUE';
      ALLOW_CONNECT='TRUE';
    'VSS31':
      PIN_NUMBER='(0,0,73)';
      PINUSE='POWER';
      NO_LOAD_CHECK='Both';
      NO_IO_CHECK='Both';
      NO_ASSERT_CHECK='TRUE';
      NO_DIR_CHECK='TRUE';
      ALLOW_CONNECT='TRUE';
    'VSS32':
      PIN_NUMBER='(0,0,75)';
      PINUSE='POWER';
      NO_LOAD_CHECK='Both';
      NO_IO_CHECK='Both';
      NO_ASSERT_CHECK='TRUE';
      NO_DIR_CHECK='TRUE';
      ALLOW_CONNECT='TRUE';
    'VSS33':
      PIN_NUMBER='(0,0,77)';
      PINUSE='POWER';
      NO_LOAD_CHECK='Both';
      NO_IO_CHECK='Both';
      NO_ASSERT_CHECK='TRUE';
      NO_DIR_CHECK='TRUE';
      ALLOW_CONNECT='TRUE';
    'VSS34':
      PIN_NUMBER='(0,0,79)';
      PINUSE='POWER';
      NO_LOAD_CHECK='Both';
      NO_IO_CHECK='Both';
      NO_ASSERT_CHECK='TRUE';
      NO_DIR_CHECK='TRUE';
      ALLOW_CONNECT='TRUE';
    'VSS35':
      PIN_NUMBER='(0,0,81)';
      PINUSE='POWER';
      NO_LOAD_CHECK='Both';
      NO_IO_CHECK='Both';
      NO_ASSERT_CHECK='TRUE';
      NO_DIR_CHECK='TRUE';
      ALLOW_CONNECT='TRUE';
    'VSS36':
      PIN_NUMBER='(0,0,83)';
      PINUSE='POWER';
      NO_LOAD_CHECK='Both';
      NO_IO_CHECK='Both';
      NO_ASSERT_CHECK='TRUE';
      NO_DIR_CHECK='TRUE';
      ALLOW_CONNECT='TRUE';
    'VSS37':
      PIN_NUMBER='(0,0,85)';
      PINUSE='POWER';
      NO_LOAD_CHECK='Both';
      NO_IO_CHECK='Both';
      NO_ASSERT_CHECK='TRUE';
      NO_DIR_CHECK='TRUE';
      ALLOW_CONNECT='TRUE';
    'VSS38':
      PIN_NUMBER='(0,0,88)';
      PINUSE='POWER';
      NO_LOAD_CHECK='Both';
      NO_IO_CHECK='Both';
      NO_ASSERT_CHECK='TRUE';
      NO_DIR_CHECK='TRUE';
      ALLOW_CONNECT='TRUE';
    'VSS39':
      PIN_NUMBER='(0,0,90)';
      PINUSE='POWER';
      NO_LOAD_CHECK='Both';
      NO_IO_CHECK='Both';
      NO_ASSERT_CHECK='TRUE';
      NO_DIR_CHECK='TRUE';
      ALLOW_CONNECT='TRUE';
    'VSS40':
      PIN_NUMBER='(0,0,92)';
      PINUSE='POWER';
      NO_LOAD_CHECK='Both';
      NO_IO_CHECK='Both';
      NO_ASSERT_CHECK='TRUE';
      NO_DIR_CHECK='TRUE';
      ALLOW_CONNECT='TRUE';
    'VSS41':
      PIN_NUMBER='(0,0,95)';
      PINUSE='POWER';
      NO_LOAD_CHECK='Both';
      NO_IO_CHECK='Both';
      NO_ASSERT_CHECK='TRUE';
      NO_DIR_CHECK='TRUE';
      ALLOW_CONNECT='TRUE';
    'VSS42':
      PIN_NUMBER='(0,0,97)';
      PINUSE='POWER';
      NO_LOAD_CHECK='Both';
      NO_IO_CHECK='Both';
      NO_ASSERT_CHECK='TRUE';
      NO_DIR_CHECK='TRUE';
      ALLOW_CONNECT='TRUE';
    'VSS43':
      PIN_NUMBER='(0,0,99)';
      PINUSE='POWER';
      NO_LOAD_CHECK='Both';
      NO_IO_CHECK='Both';
      NO_ASSERT_CHECK='TRUE';
      NO_DIR_CHECK='TRUE';
      ALLOW_CONNECT='TRUE';
    'VSS44':
      PIN_NUMBER='(0,0,101)';
      PINUSE='POWER';
      NO_LOAD_CHECK='Both';
      NO_IO_CHECK='Both';
      NO_ASSERT_CHECK='TRUE';
      NO_DIR_CHECK='TRUE';
      ALLOW_CONNECT='TRUE';
    'VSS45':
      PIN_NUMBER='(0,0,103)';
      PINUSE='POWER';
      NO_LOAD_CHECK='Both';
      NO_IO_CHECK='Both';
      NO_ASSERT_CHECK='TRUE';
      NO_DIR_CHECK='TRUE';
      ALLOW_CONNECT='TRUE';
    'VSS46':
      PIN_NUMBER='(0,0,106)';
      PINUSE='POWER';
      NO_LOAD_CHECK='Both';
      NO_IO_CHECK='Both';
      NO_ASSERT_CHECK='TRUE';
      NO_DIR_CHECK='TRUE';
      ALLOW_CONNECT='TRUE';
    'VSS47':
      PIN_NUMBER='(0,0,108)';
      PINUSE='POWER';
      NO_LOAD_CHECK='Both';
      NO_IO_CHECK='Both';
      NO_ASSERT_CHECK='TRUE';
      NO_DIR_CHECK='TRUE';
      ALLOW_CONNECT='TRUE';
    'VSS48':
      PIN_NUMBER='(0,0,110)';
      PINUSE='POWER';
      NO_LOAD_CHECK='Both';
      NO_IO_CHECK='Both';
      NO_ASSERT_CHECK='TRUE';
      NO_DIR_CHECK='TRUE';
      ALLOW_CONNECT='TRUE';
    'VSS49':
      PIN_NUMBER='(0,0,112)';
      PINUSE='POWER';
      NO_LOAD_CHECK='Both';
      NO_IO_CHECK='Both';
      NO_ASSERT_CHECK='TRUE';
      NO_DIR_CHECK='TRUE';
      ALLOW_CONNECT='TRUE';
    'VSS50':
      PIN_NUMBER='(0,0,114)';
      PINUSE='POWER';
      NO_LOAD_CHECK='Both';
      NO_IO_CHECK='Both';
      NO_ASSERT_CHECK='TRUE';
      NO_DIR_CHECK='TRUE';
      ALLOW_CONNECT='TRUE';
    'VSS51':
      PIN_NUMBER='(0,0,117)';
      PINUSE='POWER';
      NO_LOAD_CHECK='Both';
      NO_IO_CHECK='Both';
      NO_ASSERT_CHECK='TRUE';
      NO_DIR_CHECK='TRUE';
      ALLOW_CONNECT='TRUE';
    'VSS52':
      PIN_NUMBER='(0,0,119)';
      PINUSE='POWER';
      NO_LOAD_CHECK='Both';
      NO_IO_CHECK='Both';
      NO_ASSERT_CHECK='TRUE';
      NO_DIR_CHECK='TRUE';
      ALLOW_CONNECT='TRUE';
    'VSS53':
      PIN_NUMBER='(0,0,121)';
      PINUSE='POWER';
      NO_LOAD_CHECK='Both';
      NO_IO_CHECK='Both';
      NO_ASSERT_CHECK='TRUE';
      NO_DIR_CHECK='TRUE';
      ALLOW_CONNECT='TRUE';
    'VSS54':
      PIN_NUMBER='(0,0,123)';
      PINUSE='POWER';
      NO_LOAD_CHECK='Both';
      NO_IO_CHECK='Both';
      NO_ASSERT_CHECK='TRUE';
      NO_DIR_CHECK='TRUE';
      ALLOW_CONNECT='TRUE';
    'VSS55':
      PIN_NUMBER='(0,0,125)';
      PINUSE='POWER';
      NO_LOAD_CHECK='Both';
      NO_IO_CHECK='Both';
      NO_ASSERT_CHECK='TRUE';
      NO_DIR_CHECK='TRUE';
      ALLOW_CONNECT='TRUE';
    'VSS56':
      PIN_NUMBER='(0,0,128)';
      PINUSE='POWER';
      NO_LOAD_CHECK='Both';
      NO_IO_CHECK='Both';
      NO_ASSERT_CHECK='TRUE';
      NO_DIR_CHECK='TRUE';
      ALLOW_CONNECT='TRUE';
    'VSS57':
      PIN_NUMBER='(0,0,130)';
      PINUSE='POWER';
      NO_LOAD_CHECK='Both';
      NO_IO_CHECK='Both';
      NO_ASSERT_CHECK='TRUE';
      NO_DIR_CHECK='TRUE';
      ALLOW_CONNECT='TRUE';
    'VSS59':
      PIN_NUMBER='(0,0,134)';
      PINUSE='POWER';
      NO_LOAD_CHECK='Both';
      NO_IO_CHECK='Both';
      NO_ASSERT_CHECK='TRUE';
      NO_DIR_CHECK='TRUE';
      ALLOW_CONNECT='TRUE';
    'VSS63':
      PIN_NUMBER='(0,0,143)';
      PINUSE='POWER';
      NO_LOAD_CHECK='Both';
      NO_IO_CHECK='Both';
      NO_ASSERT_CHECK='TRUE';
      NO_DIR_CHECK='TRUE';
      ALLOW_CONNECT='TRUE';
    'VSS64':
      PIN_NUMBER='(0,0,151)';
      PINUSE='POWER';
      NO_LOAD_CHECK='Both';
      NO_IO_CHECK='Both';
      NO_ASSERT_CHECK='TRUE';
      NO_DIR_CHECK='TRUE';
      ALLOW_CONNECT='TRUE';
    'VSS65':
      PIN_NUMBER='(0,0,153)';
      PINUSE='POWER';
      NO_LOAD_CHECK='Both';
      NO_IO_CHECK='Both';
      NO_ASSERT_CHECK='TRUE';
      NO_DIR_CHECK='TRUE';
      ALLOW_CONNECT='TRUE';
    'VSS66':
      PIN_NUMBER='(0,0,155)';
      PINUSE='POWER';
      NO_LOAD_CHECK='Both';
      NO_IO_CHECK='Both';
      NO_ASSERT_CHECK='TRUE';
      NO_DIR_CHECK='TRUE';
      ALLOW_CONNECT='TRUE';
    'VSS67':
      PIN_NUMBER='(0,0,158)';
      PINUSE='POWER';
      NO_LOAD_CHECK='Both';
      NO_IO_CHECK='Both';
      NO_ASSERT_CHECK='TRUE';
      NO_DIR_CHECK='TRUE';
      ALLOW_CONNECT='TRUE';
    'VSS68':
      PIN_NUMBER='(0,0,160)';
      PINUSE='POWER';
      NO_LOAD_CHECK='Both';
      NO_IO_CHECK='Both';
      NO_ASSERT_CHECK='TRUE';
      NO_DIR_CHECK='TRUE';
      ALLOW_CONNECT='TRUE';
    'VSS69':
      PIN_NUMBER='(0,0,162)';
      PINUSE='POWER';
      NO_LOAD_CHECK='Both';
      NO_IO_CHECK='Both';
      NO_ASSERT_CHECK='TRUE';
      NO_DIR_CHECK='TRUE';
      ALLOW_CONNECT='TRUE';
    'VSS70':
      PIN_NUMBER='(0,0,164)';
      PINUSE='POWER';
      NO_LOAD_CHECK='Both';
      NO_IO_CHECK='Both';
      NO_ASSERT_CHECK='TRUE';
      NO_DIR_CHECK='TRUE';
      ALLOW_CONNECT='TRUE';
    'VSS71':
      PIN_NUMBER='(0,0,166)';
      PINUSE='POWER';
      NO_LOAD_CHECK='Both';
      NO_IO_CHECK='Both';
      NO_ASSERT_CHECK='TRUE';
      NO_DIR_CHECK='TRUE';
      ALLOW_CONNECT='TRUE';
    'VSS72':
      PIN_NUMBER='(0,0,169)';
      PINUSE='POWER';
      NO_LOAD_CHECK='Both';
      NO_IO_CHECK='Both';
      NO_ASSERT_CHECK='TRUE';
      NO_DIR_CHECK='TRUE';
      ALLOW_CONNECT='TRUE';
    'VSS73':
      PIN_NUMBER='(0,0,171)';
      PINUSE='POWER';
      NO_LOAD_CHECK='Both';
      NO_IO_CHECK='Both';
      NO_ASSERT_CHECK='TRUE';
      NO_DIR_CHECK='TRUE';
      ALLOW_CONNECT='TRUE';
    'VSS74':
      PIN_NUMBER='(0,0,173)';
      PINUSE='POWER';
      NO_LOAD_CHECK='Both';
      NO_IO_CHECK='Both';
      NO_ASSERT_CHECK='TRUE';
      NO_DIR_CHECK='TRUE';
      ALLOW_CONNECT='TRUE';
    'VSS75':
      PIN_NUMBER='(0,0,175)';
      PINUSE='POWER';
      NO_LOAD_CHECK='Both';
      NO_IO_CHECK='Both';
      NO_ASSERT_CHECK='TRUE';
      NO_DIR_CHECK='TRUE';
      ALLOW_CONNECT='TRUE';
    'VSS76':
      PIN_NUMBER='(0,0,177)';
      PINUSE='POWER';
      NO_LOAD_CHECK='Both';
      NO_IO_CHECK='Both';
      NO_ASSERT_CHECK='TRUE';
      NO_DIR_CHECK='TRUE';
      ALLOW_CONNECT='TRUE';
    'VSS77':
      PIN_NUMBER='(0,0,180)';
      PINUSE='POWER';
      NO_LOAD_CHECK='Both';
      NO_IO_CHECK='Both';
      NO_ASSERT_CHECK='TRUE';
      NO_DIR_CHECK='TRUE';
      ALLOW_CONNECT='TRUE';
    'VSS78':
      PIN_NUMBER='(0,0,182)';
      PINUSE='POWER';
      NO_LOAD_CHECK='Both';
      NO_IO_CHECK='Both';
      NO_ASSERT_CHECK='TRUE';
      NO_DIR_CHECK='TRUE';
      ALLOW_CONNECT='TRUE';
    'VSS79':
      PIN_NUMBER='(0,0,184)';
      PINUSE='POWER';
      NO_LOAD_CHECK='Both';
      NO_IO_CHECK='Both';
      NO_ASSERT_CHECK='TRUE';
      NO_DIR_CHECK='TRUE';
      ALLOW_CONNECT='TRUE';
    'VSS80':
      PIN_NUMBER='(0,0,186)';
      PINUSE='POWER';
      NO_LOAD_CHECK='Both';
      NO_IO_CHECK='Both';
      NO_ASSERT_CHECK='TRUE';
      NO_DIR_CHECK='TRUE';
      ALLOW_CONNECT='TRUE';
    'VSS81':
      PIN_NUMBER='(0,0,188)';
      PINUSE='POWER';
      NO_LOAD_CHECK='Both';
      NO_IO_CHECK='Both';
      NO_ASSERT_CHECK='TRUE';
      NO_DIR_CHECK='TRUE';
      ALLOW_CONNECT='TRUE';
    'VSS82':
      PIN_NUMBER='(0,0,191)';
      PINUSE='POWER';
      NO_LOAD_CHECK='Both';
      NO_IO_CHECK='Both';
      NO_ASSERT_CHECK='TRUE';
      NO_DIR_CHECK='TRUE';
      ALLOW_CONNECT='TRUE';
    'VSS83':
      PIN_NUMBER='(0,0,193)';
      PINUSE='POWER';
      NO_LOAD_CHECK='Both';
      NO_IO_CHECK='Both';
      NO_ASSERT_CHECK='TRUE';
      NO_DIR_CHECK='TRUE';
      ALLOW_CONNECT='TRUE';
    'VSS84':
      PIN_NUMBER='(0,0,195)';
      PINUSE='POWER';
      NO_LOAD_CHECK='Both';
      NO_IO_CHECK='Both';
      NO_ASSERT_CHECK='TRUE';
      NO_DIR_CHECK='TRUE';
      ALLOW_CONNECT='TRUE';
    'VSS85':
      PIN_NUMBER='(0,0,197)';
      PINUSE='POWER';
      NO_LOAD_CHECK='Both';
      NO_IO_CHECK='Both';
      NO_ASSERT_CHECK='TRUE';
      NO_DIR_CHECK='TRUE';
      ALLOW_CONNECT='TRUE';
    'VSS86':
      PIN_NUMBER='(0,0,199)';
      PINUSE='POWER';
      NO_LOAD_CHECK='Both';
      NO_IO_CHECK='Both';
      NO_ASSERT_CHECK='TRUE';
      NO_DIR_CHECK='TRUE';
      ALLOW_CONNECT='TRUE';
    'VSS87':
      PIN_NUMBER='(0,0,202)';
      PINUSE='POWER';
      NO_LOAD_CHECK='Both';
      NO_IO_CHECK='Both';
      NO_ASSERT_CHECK='TRUE';
      NO_DIR_CHECK='TRUE';
      ALLOW_CONNECT='TRUE';
    'VSS88':
      PIN_NUMBER='(0,0,204)';
      PINUSE='POWER';
      NO_LOAD_CHECK='Both';
      NO_IO_CHECK='Both';
      NO_ASSERT_CHECK='TRUE';
      NO_DIR_CHECK='TRUE';
      ALLOW_CONNECT='TRUE';
    'VSS89':
      PIN_NUMBER='(0,0,206)';
      PINUSE='POWER';
      NO_LOAD_CHECK='Both';
      NO_IO_CHECK='Both';
      NO_ASSERT_CHECK='TRUE';
      NO_DIR_CHECK='TRUE';
      ALLOW_CONNECT='TRUE';
    'VSS90':
      PIN_NUMBER='(0,0,208)';
      PINUSE='POWER';
      NO_LOAD_CHECK='Both';
      NO_IO_CHECK='Both';
      NO_ASSERT_CHECK='TRUE';
      NO_DIR_CHECK='TRUE';
      ALLOW_CONNECT='TRUE';
    'VSS91':
      PIN_NUMBER='(0,0,210)';
      PINUSE='POWER';
      NO_LOAD_CHECK='Both';
      NO_IO_CHECK='Both';
      NO_ASSERT_CHECK='TRUE';
      NO_DIR_CHECK='TRUE';
      ALLOW_CONNECT='TRUE';
    'VSS92':
      PIN_NUMBER='(0,0,212)';
      PINUSE='POWER';
      NO_LOAD_CHECK='Both';
      NO_IO_CHECK='Both';
      NO_ASSERT_CHECK='TRUE';
      NO_DIR_CHECK='TRUE';
      ALLOW_CONNECT='TRUE';
    'VSS93':
      PIN_NUMBER='(0,0,214)';
      PINUSE='POWER';
      NO_LOAD_CHECK='Both';
      NO_IO_CHECK='Both';
      NO_ASSERT_CHECK='TRUE';
      NO_DIR_CHECK='TRUE';
      ALLOW_CONNECT='TRUE';
    'VSS94':
      PIN_NUMBER='(0,0,216)';
      PINUSE='POWER';
      NO_LOAD_CHECK='Both';
      NO_IO_CHECK='Both';
      NO_ASSERT_CHECK='TRUE';
      NO_DIR_CHECK='TRUE';
      ALLOW_CONNECT='TRUE';
    'VSS95':
      PIN_NUMBER='(0,0,219)';
      PINUSE='POWER';
      NO_LOAD_CHECK='Both';
      NO_IO_CHECK='Both';
      NO_ASSERT_CHECK='TRUE';
      NO_DIR_CHECK='TRUE';
      ALLOW_CONNECT='TRUE';
    'VSS96':
      PIN_NUMBER='(0,0,222)';
      PINUSE='POWER';
      NO_LOAD_CHECK='Both';
      NO_IO_CHECK='Both';
      NO_ASSERT_CHECK='TRUE';
      NO_DIR_CHECK='TRUE';
      ALLOW_CONNECT='TRUE';
    'VSS97':
      PIN_NUMBER='(0,0,224)';
      PINUSE='POWER';
      NO_LOAD_CHECK='Both';
      NO_IO_CHECK='Both';
      NO_ASSERT_CHECK='TRUE';
      NO_DIR_CHECK='TRUE';
      ALLOW_CONNECT='TRUE';
    'VSS98':
      PIN_NUMBER='(0,0,226)';
      PINUSE='POWER';
      NO_LOAD_CHECK='Both';
      NO_IO_CHECK='Both';
      NO_ASSERT_CHECK='TRUE';
      NO_DIR_CHECK='TRUE';
      ALLOW_CONNECT='TRUE';
    'VSS99':
      PIN_NUMBER='(0,0,228)';
      PINUSE='POWER';
      NO_LOAD_CHECK='Both';
      NO_IO_CHECK='Both';
      NO_ASSERT_CHECK='TRUE';
      NO_DIR_CHECK='TRUE';
      ALLOW_CONNECT='TRUE';
    'VSS101':
      PIN_NUMBER='(0,0,233)';
      PINUSE='POWER';
      NO_LOAD_CHECK='Both';
      NO_IO_CHECK='Both';
      NO_ASSERT_CHECK='TRUE';
      NO_DIR_CHECK='TRUE';
      ALLOW_CONNECT='TRUE';
    'VSS103':
      PIN_NUMBER='(0,0,237)';
      PINUSE='POWER';
      NO_LOAD_CHECK='Both';
      NO_IO_CHECK='Both';
      NO_ASSERT_CHECK='TRUE';
      NO_DIR_CHECK='TRUE';
      ALLOW_CONNECT='TRUE';
    'VSS105':
      PIN_NUMBER='(0,0,242)';
      PINUSE='POWER';
      NO_LOAD_CHECK='Both';
      NO_IO_CHECK='Both';
      NO_ASSERT_CHECK='TRUE';
      NO_DIR_CHECK='TRUE';
      ALLOW_CONNECT='TRUE';
    'VSS106':
      PIN_NUMBER='(0,0,244)';
      PINUSE='POWER';
      NO_LOAD_CHECK='Both';
      NO_IO_CHECK='Both';
      NO_ASSERT_CHECK='TRUE';
      NO_DIR_CHECK='TRUE';
      ALLOW_CONNECT='TRUE';
    'VSS107':
      PIN_NUMBER='(0,0,246)';
      PINUSE='POWER';
      NO_LOAD_CHECK='Both';
      NO_IO_CHECK='Both';
      NO_ASSERT_CHECK='TRUE';
      NO_DIR_CHECK='TRUE';
      ALLOW_CONNECT='TRUE';
    'VSS108':
      PIN_NUMBER='(0,0,248)';
      PINUSE='POWER';
      NO_LOAD_CHECK='Both';
      NO_IO_CHECK='Both';
      NO_ASSERT_CHECK='TRUE';
      NO_DIR_CHECK='TRUE';
      ALLOW_CONNECT='TRUE';
    'VSS109':
      PIN_NUMBER='(0,0,251)';
      PINUSE='POWER';
      NO_LOAD_CHECK='Both';
      NO_IO_CHECK='Both';
      NO_ASSERT_CHECK='TRUE';
      NO_DIR_CHECK='TRUE';
      ALLOW_CONNECT='TRUE';
    'VSS110':
      PIN_NUMBER='(0,0,253)';
      PINUSE='POWER';
      NO_LOAD_CHECK='Both';
      NO_IO_CHECK='Both';
      NO_ASSERT_CHECK='TRUE';
      NO_DIR_CHECK='TRUE';
      ALLOW_CONNECT='TRUE';
    'VSS111':
      PIN_NUMBER='(0,0,255)';
      PINUSE='POWER';
      NO_LOAD_CHECK='Both';
      NO_IO_CHECK='Both';
      NO_ASSERT_CHECK='TRUE';
      NO_DIR_CHECK='TRUE';
      ALLOW_CONNECT='TRUE';
    'VSS112':
      PIN_NUMBER='(0,0,257)';
      PINUSE='POWER';
      NO_LOAD_CHECK='Both';
      NO_IO_CHECK='Both';
      NO_ASSERT_CHECK='TRUE';
      NO_DIR_CHECK='TRUE';
      ALLOW_CONNECT='TRUE';
    'VSS113':
      PIN_NUMBER='(0,0,259)';
      PINUSE='POWER';
      NO_LOAD_CHECK='Both';
      NO_IO_CHECK='Both';
      NO_ASSERT_CHECK='TRUE';
      NO_DIR_CHECK='TRUE';
      ALLOW_CONNECT='TRUE';
    'VSS114':
      PIN_NUMBER='(0,0,262)';
      PINUSE='POWER';
      NO_LOAD_CHECK='Both';
      NO_IO_CHECK='Both';
      NO_ASSERT_CHECK='TRUE';
      NO_DIR_CHECK='TRUE';
      ALLOW_CONNECT='TRUE';
    'VSS115':
      PIN_NUMBER='(0,0,264)';
      PINUSE='POWER';
      NO_LOAD_CHECK='Both';
      NO_IO_CHECK='Both';
      NO_ASSERT_CHECK='TRUE';
      NO_DIR_CHECK='TRUE';
      ALLOW_CONNECT='TRUE';
    'VSS116':
      PIN_NUMBER='(0,0,266)';
      PINUSE='POWER';
      NO_LOAD_CHECK='Both';
      NO_IO_CHECK='Both';
      NO_ASSERT_CHECK='TRUE';
      NO_DIR_CHECK='TRUE';
      ALLOW_CONNECT='TRUE';
    'VSS117':
      PIN_NUMBER='(0,0,268)';
      PINUSE='POWER';
      NO_LOAD_CHECK='Both';
      NO_IO_CHECK='Both';
      NO_ASSERT_CHECK='TRUE';
      NO_DIR_CHECK='TRUE';
      ALLOW_CONNECT='TRUE';
    'VSS118':
      PIN_NUMBER='(0,0,270)';
      PINUSE='POWER';
      NO_LOAD_CHECK='Both';
      NO_IO_CHECK='Both';
      NO_ASSERT_CHECK='TRUE';
      NO_DIR_CHECK='TRUE';
      ALLOW_CONNECT='TRUE';
    'VSS119':
      PIN_NUMBER='(0,0,273)';
      PINUSE='POWER';
      NO_LOAD_CHECK='Both';
      NO_IO_CHECK='Both';
      NO_ASSERT_CHECK='TRUE';
      NO_DIR_CHECK='TRUE';
      ALLOW_CONNECT='TRUE';
    'VSS120':
      PIN_NUMBER='(0,0,275)';
      PINUSE='POWER';
      NO_LOAD_CHECK='Both';
      NO_IO_CHECK='Both';
      NO_ASSERT_CHECK='TRUE';
      NO_DIR_CHECK='TRUE';
      ALLOW_CONNECT='TRUE';
    'VSS121':
      PIN_NUMBER='(0,0,277)';
      PINUSE='POWER';
      NO_LOAD_CHECK='Both';
      NO_IO_CHECK='Both';
      NO_ASSERT_CHECK='TRUE';
      NO_DIR_CHECK='TRUE';
      ALLOW_CONNECT='TRUE';
    'VSS122':
      PIN_NUMBER='(0,0,279)';
      PINUSE='POWER';
      NO_LOAD_CHECK='Both';
      NO_IO_CHECK='Both';
      NO_ASSERT_CHECK='TRUE';
      NO_DIR_CHECK='TRUE';
      ALLOW_CONNECT='TRUE';
    'VSS123':
      PIN_NUMBER='(0,0,281)';
      PINUSE='POWER';
      NO_LOAD_CHECK='Both';
      NO_IO_CHECK='Both';
      NO_ASSERT_CHECK='TRUE';
      NO_DIR_CHECK='TRUE';
      ALLOW_CONNECT='TRUE';
    'VSS124':
      PIN_NUMBER='(0,0,284)';
      PINUSE='POWER';
      NO_LOAD_CHECK='Both';
      NO_IO_CHECK='Both';
      NO_ASSERT_CHECK='TRUE';
      NO_DIR_CHECK='TRUE';
      ALLOW_CONNECT='TRUE';
    'VSS125':
      PIN_NUMBER='(0,0,286)';
      PINUSE='POWER';
      NO_LOAD_CHECK='Both';
      NO_IO_CHECK='Both';
      NO_ASSERT_CHECK='TRUE';
      NO_DIR_CHECK='TRUE';
      ALLOW_CONNECT='TRUE';
    'VSS126':
      PIN_NUMBER='(0,0,288)';
      PINUSE='POWER';
      NO_LOAD_CHECK='Both';
      NO_IO_CHECK='Both';
      NO_ASSERT_CHECK='TRUE';
      NO_DIR_CHECK='TRUE';
      ALLOW_CONNECT='TRUE';
    'VIN_BULK0':
      PIN_NUMBER='(0,0,1)';
      PINUSE='POWER';
      NO_LOAD_CHECK='Both';
      NO_IO_CHECK='Both';
      NO_ASSERT_CHECK='TRUE';
      NO_DIR_CHECK='TRUE';
      ALLOW_CONNECT='TRUE';
    'VIN_BULK1':
      PIN_NUMBER='(0,0,145)';
      PINUSE='POWER';
      NO_LOAD_CHECK='Both';
      NO_IO_CHECK='Both';
      NO_ASSERT_CHECK='TRUE';
      NO_DIR_CHECK='TRUE';
      ALLOW_CONNECT='TRUE';
    'VIN_BULK2':
      PIN_NUMBER='(0,0,146)';
      PINUSE='POWER';
      NO_LOAD_CHECK='Both';
      NO_IO_CHECK='Both';
      NO_ASSERT_CHECK='TRUE';
      NO_DIR_CHECK='TRUE';
      ALLOW_CONNECT='TRUE';
    'VSS100':
      PIN_NUMBER='(0,0,230)';
      PINUSE='POWER';
      NO_LOAD_CHECK='Both';
      NO_IO_CHECK='Both';
      NO_ASSERT_CHECK='TRUE';
      NO_DIR_CHECK='TRUE';
      ALLOW_CONNECT='TRUE';
    'VSS102':
      PIN_NUMBER='(0,0,235)';
      PINUSE='POWER';
      NO_LOAD_CHECK='Both';
      NO_IO_CHECK='Both';
      NO_ASSERT_CHECK='TRUE';
      NO_DIR_CHECK='TRUE';
      ALLOW_CONNECT='TRUE';
    'VSS104':
      PIN_NUMBER='(0,0,240)';
      PINUSE='POWER';
      NO_LOAD_CHECK='Both';
      NO_IO_CHECK='Both';
      NO_ASSERT_CHECK='TRUE';
      NO_DIR_CHECK='TRUE';
      ALLOW_CONNECT='TRUE';
    'VSS58':
      PIN_NUMBER='(0,0,132)';
      PINUSE='POWER';
      NO_LOAD_CHECK='Both';
      NO_IO_CHECK='Both';
      NO_ASSERT_CHECK='TRUE';
      NO_DIR_CHECK='TRUE';
      ALLOW_CONNECT='TRUE';
    'VSS60':
      PIN_NUMBER='(0,0,136)';
      PINUSE='POWER';
      NO_LOAD_CHECK='Both';
      NO_IO_CHECK='Both';
      NO_ASSERT_CHECK='TRUE';
      NO_DIR_CHECK='TRUE';
      ALLOW_CONNECT='TRUE';
    'VSS61':
      PIN_NUMBER='(0,0,139)';
      PINUSE='POWER';
      NO_LOAD_CHECK='Both';
      NO_IO_CHECK='Both';
      NO_ASSERT_CHECK='TRUE';
      NO_DIR_CHECK='TRUE';
      ALLOW_CONNECT='TRUE';
    'VSS62':
      PIN_NUMBER='(0,0,141)';
      PINUSE='POWER';
      NO_LOAD_CHECK='Both';
      NO_IO_CHECK='Both';
      NO_ASSERT_CHECK='TRUE';
      NO_DIR_CHECK='TRUE';
      ALLOW_CONNECT='TRUE';
    'G1':
      PIN_NUMBER='(0,0,G1)';
      PINUSE='POWER';
      NO_LOAD_CHECK='Both';
      NO_IO_CHECK='Both';
      NO_ASSERT_CHECK='TRUE';
      NO_DIR_CHECK='TRUE';
      ALLOW_CONNECT='TRUE';
    'G2':
      PIN_NUMBER='(0,0,G2)';
      PINUSE='POWER';
      NO_LOAD_CHECK='Both';
      NO_IO_CHECK='Both';
      NO_ASSERT_CHECK='TRUE';
      NO_DIR_CHECK='TRUE';
      ALLOW_CONNECT='TRUE';
    'G3':
      PIN_NUMBER='(0,0,G3)';
      PINUSE='POWER';
      NO_LOAD_CHECK='Both';
      NO_IO_CHECK='Both';
      NO_ASSERT_CHECK='TRUE';
      NO_DIR_CHECK='TRUE';
      ALLOW_CONNECT='TRUE';
  end_pin;
  body
    PART_NAME='SCONN288_ADR50017P087CC';
    BODY_NAME='SCONN288_ADR50017P087CC';
    PHYS_DES_PREFIX='J';
    CLASS='IO';
  end_body;
end_primitive;

END.
